(kicad_pcb
	(version 20260206)
	(generator "pcbnew")
	(generator_version "10.0")
	(general
		(thickness 1.6)
		(legacy_teardrops no)
	)
	(paper "A4")
	(title_block
		(title "01162023_DA0F0TEBIF0_F0T_Expander_BD_F_brd_V02_OCP.brd")
		(comment 1 "Grand Teton / footprints 1507-1514 of 9728")
	)
	(layers
		(0 "F.Cu" signal "TOP")
		(4 "In1.Cu" signal "GND")
		(6 "In2.Cu" signal "VCC")
		(8 "In3.Cu" signal "VCC1")
		(10 "In4.Cu" signal "GND1")
		(12 "In5.Cu" signal "IN1")
		(14 "In6.Cu" signal "GND2")
		(16 "In7.Cu" signal "IN2")
		(18 "In8.Cu" signal "GND3")
		(20 "In9.Cu" signal "IN3")
		(22 "In10.Cu" signal "GND4")
		(24 "In11.Cu" signal "IN4")
		(26 "In12.Cu" signal "GND5")
		(28 "In13.Cu" signal "IN5")
		(30 "In14.Cu" signal "GND6")
		(32 "In15.Cu" signal "IN6")
		(34 "In16.Cu" signal "GND7")
		(2 "B.Cu" signal "BOTTOM")
		(9 "F.Adhes" user "F.Adhesive")
		(11 "B.Adhes" user "B.Adhesive")
		(13 "F.Paste" user "Package Geometry/Pastemask Top")
		(15 "B.Paste" user "Package Geometry/Pastemask Bottom")
		(5 "F.SilkS" user "Ref Des/Silkscreen Top")
		(7 "B.SilkS" user "Ref Des/Silkscreen Bottom")
		(1 "F.Mask" user "Board Geometry/Soldermask Top")
		(3 "B.Mask" user "Board Geometry/Soldermask Bottom")
		(17 "Dwgs.User" user "User.Drawings")
		(19 "Cmts.User" user "User.Comments")
		(21 "Eco1.User" user "User.Eco1")
		(23 "Eco2.User" user "User.Eco2")
		(25 "Edge.Cuts" user "Board Geometry/Outline")
		(27 "Margin" user)
		(31 "F.CrtYd" user "Package Geometry/Place Bound Top")
		(29 "B.CrtYd" user "Package Geometry/Place Bound Bottom")
		(35 "F.Fab" user "Ref Des/Assembly Top")
		(33 "B.Fab" user "Ref Des/Assembly Bottom")
	)
	(footprint ""
		(layer "F.Cu")
		(at 198.76135 -156.111194 180)
		(property "Reference" "C212"
			(at 0 0 180)
			(layer "F.SilkS")
			(hide yes)
			(effects
				(font
					(size 1.27 1.27)
				)
			)
		)
		(property "Value" ""
			(at 0 0 180)
			(layer "F.Fab")
			(effects
				(font
					(size 1.27 1.27)
				)
			)
		)
		(duplicate_pad_numbers_are_jumpers no)
		(fp_line
			(start 0.299974 0.150114)
			(end -0.299974 0.150114)
			(stroke
				(width 0.1)
				(type default)
			)
			(layer "F.Fab")
		)
		(fp_line
			(start 0.299974 -0.150114)
			(end 0.299974 0.150114)
			(stroke
				(width 0.1)
				(type default)
			)
			(layer "F.Fab")
		)
		(fp_line
			(start -0.299974 0.150114)
			(end -0.299974 -0.150114)
			(stroke
				(width 0.1)
				(type default)
			)
			(layer "F.Fab")
		)
		(fp_line
			(start -0.299974 -0.150114)
			(end 0.299974 -0.150114)
			(stroke
				(width 0.1)
				(type default)
			)
			(layer "F.Fab")
		)
		(pad "1" smd rect
			(at -0.2667 0 180)
			(size 0.3048 0.381)
			(layers "F.Cu" "F.Mask" "F.Paste")
			(net "P5E_PEX1_STN0_TX_DP<15>")
		)
		(pad "2" smd rect
			(at 0.2667 0 180)
			(size 0.3048 0.381)
			(layers "F.Cu" "F.Mask" "F.Paste")
			(net "P5E_PEX1_STN0_TX_C_DP<15>")
		)
	)
	(footprint ""
		(layer "F.Cu")
		(at 456.818238 -266.996672)
		(property "Reference" "R6141"
			(at 0 0 0)
			(layer "F.SilkS")
			(hide yes)
			(effects
				(font
					(size 1.27 1.27)
				)
			)
		)
		(property "Value" ""
			(at 0 0 0)
			(layer "F.Fab")
			(effects
				(font
					(size 1.27 1.27)
				)
			)
		)
		(duplicate_pad_numbers_are_jumpers no)
		(fp_line
			(start -2.576322 -1.1303)
			(end 2.576322 -1.1303)
			(stroke
				(width 0.1524)
				(type default)
			)
			(layer "F.SilkS")
		)
		(fp_line
			(start -2.576322 1.1303)
			(end -2.576322 -1.1303)
			(stroke
				(width 0.1524)
				(type default)
			)
			(layer "F.SilkS")
		)
		(fp_line
			(start 2.576322 -1.1303)
			(end 2.576322 1.1303)
			(stroke
				(width 0.1524)
				(type default)
			)
			(layer "F.SilkS")
		)
		(fp_line
			(start 2.576322 1.1303)
			(end -2.576322 1.1303)
			(stroke
				(width 0.1524)
				(type default)
			)
			(layer "F.SilkS")
		)
		(fp_line
			(start -1.649984 -0.899922)
			(end -1.649984 0.899922)
			(stroke
				(width 0.1)
				(type default)
			)
			(layer "F.Fab")
		)
		(fp_line
			(start -1.649984 0.899922)
			(end 1.649984 0.899922)
			(stroke
				(width 0.1)
				(type default)
			)
			(layer "F.Fab")
		)
		(fp_line
			(start 1.649984 -0.899922)
			(end -1.649984 -0.899922)
			(stroke
				(width 0.1)
				(type default)
			)
			(layer "F.Fab")
		)
		(fp_line
			(start 1.649984 0.899922)
			(end 1.649984 -0.899922)
			(stroke
				(width 0.1)
				(type default)
			)
			(layer "F.Fab")
		)
		(pad "1A" smd rect
			(at -1.700022 0)
			(size 1.4986 2.0066)
			(layers "F.Cu" "F.Mask" "F.Paste")
			(net "P1V25_PEX3")
		)
		(pad "1B" smd rect
			(at -1.077722 0)
			(size 0.254 0.508)
			(layers "F.Cu" "F.Mask" "F.Paste")
			(net "P1V25_PEX3")
		)
		(pad "2A" smd rect
			(at 1.700022 0)
			(size 1.4986 2.0066)
			(layers "F.Cu" "F.Mask" "F.Paste")
			(net "P1V25_SERDES_VDDPLL_PEX3")
		)
		(pad "2B" smd rect
			(at 1.077722 0)
			(size 0.254 0.508)
			(layers "F.Cu" "F.Mask" "F.Paste")
			(net "P1V25_SERDES_VDDPLL_PEX3")
		)
	)
	(footprint ""
		(layer "F.Cu")
		(at 67.564762 -343.952322 90)
		(property "Reference" "C133"
			(at 0 0 90)
			(layer "F.SilkS")
			(hide yes)
			(effects
				(font
					(size 1.27 1.27)
				)
			)
		)
		(property "Value" ""
			(at 0 0 90)
			(layer "F.Fab")
			(effects
				(font
					(size 1.27 1.27)
				)
			)
		)
		(duplicate_pad_numbers_are_jumpers no)
		(fp_line
			(start 0.299974 -0.150114)
			(end 0.299974 0.150114)
			(stroke
				(width 0.1)
				(type default)
			)
			(layer "F.Fab")
		)
		(fp_line
			(start -0.299974 -0.150114)
			(end 0.299974 -0.150114)
			(stroke
				(width 0.1)
				(type default)
			)
			(layer "F.Fab")
		)
		(fp_line
			(start 0.299974 0.150114)
			(end -0.299974 0.150114)
			(stroke
				(width 0.1)
				(type default)
			)
			(layer "F.Fab")
		)
		(fp_line
			(start -0.299974 0.150114)
			(end -0.299974 -0.150114)
			(stroke
				(width 0.1)
				(type default)
			)
			(layer "F.Fab")
		)
		(pad "1" smd rect
			(at -0.2667 0 90)
			(size 0.3048 0.381)
			(layers "F.Cu" "F.Mask" "F.Paste")
			(net "P5E_PEX0_STN6_TX_DP<109>")
		)
		(pad "2" smd rect
			(at 0.2667 0 90)
			(size 0.3048 0.381)
			(layers "F.Cu" "F.Mask" "F.Paste")
			(net "P5E_PEX0_STN6_TX_C_DP<109>")
		)
	)
	(footprint ""
		(layer "F.Cu")
		(at 19.258026 -72.766682 90)
		(property "Reference" "PC641"
			(at 0 0 90)
			(layer "F.SilkS")
			(hide yes)
			(effects
				(font
					(size 1.27 1.27)
				)
			)
		)
		(property "Value" ""
			(at 0 0 90)
			(layer "F.Fab")
			(effects
				(font
					(size 1.27 1.27)
				)
			)
		)
		(duplicate_pad_numbers_are_jumpers no)
		(fp_line
			(start 0.7874 -0.4064)
			(end 0.7874 0.4064)
			(stroke
				(width 0.1524)
				(type default)
			)
			(layer "F.SilkS")
		)
		(fp_line
			(start -0.7874 -0.4064)
			(end 0.7874 -0.4064)
			(stroke
				(width 0.1524)
				(type default)
			)
			(layer "F.SilkS")
		)
		(fp_line
			(start 0.7874 0.4064)
			(end -0.7874 0.4064)
			(stroke
				(width 0.1524)
				(type default)
			)
			(layer "F.SilkS")
		)
		(fp_line
			(start -0.7874 0.4064)
			(end -0.7874 -0.4064)
			(stroke
				(width 0.1524)
				(type default)
			)
			(layer "F.SilkS")
		)
		(fp_line
			(start -0.12065 -0.305054)
			(end -0.12065 -0.2794)
			(stroke
				(width 0.1)
				(type default)
			)
			(layer "F.Fab")
		)
		(fp_line
			(start -0.67945 -0.305054)
			(end -0.12065 -0.305054)
			(stroke
				(width 0.1)
				(type default)
			)
			(layer "F.Fab")
		)
		(fp_line
			(start 0.67945 -0.3048)
			(end 0.67945 0.3048)
			(stroke
				(width 0.1)
				(type default)
			)
			(layer "F.Fab")
		)
		(fp_line
			(start 0.12065 -0.3048)
			(end 0.67945 -0.3048)
			(stroke
				(width 0.1)
				(type default)
			)
			(layer "F.Fab")
		)
		(fp_line
			(start 0.12065 -0.2794)
			(end 0.12065 -0.3048)
			(stroke
				(width 0.1)
				(type default)
			)
			(layer "F.Fab")
		)
		(fp_line
			(start -0.12065 -0.2794)
			(end 0.12065 -0.2794)
			(stroke
				(width 0.1)
				(type default)
			)
			(layer "F.Fab")
		)
		(fp_line
			(start 0.120396 0.2794)
			(end -0.12065 0.2794)
			(stroke
				(width 0.1)
				(type default)
			)
			(layer "F.Fab")
		)
		(fp_line
			(start -0.12065 0.2794)
			(end -0.12065 0.3048)
			(stroke
				(width 0.1)
				(type default)
			)
			(layer "F.Fab")
		)
		(fp_line
			(start 0.67945 0.3048)
			(end 0.120396 0.3048)
			(stroke
				(width 0.1)
				(type default)
			)
			(layer "F.Fab")
		)
		(fp_line
			(start 0.120396 0.3048)
			(end 0.120396 0.2794)
			(stroke
				(width 0.1)
				(type default)
			)
			(layer "F.Fab")
		)
		(fp_line
			(start -0.12065 0.3048)
			(end -0.67945 0.3048)
			(stroke
				(width 0.1)
				(type default)
			)
			(layer "F.Fab")
		)
		(fp_line
			(start -0.67945 0.3048)
			(end -0.67945 -0.305054)
			(stroke
				(width 0.1)
				(type default)
			)
			(layer "F.Fab")
		)
		(pad "1" smd circle
			(at -0.40005 0 90)
			(size 0 0)
			(layers "F.Cu" "F.Mask" "F.Paste")
			(net "P12V_SSD0_CO_MODE")
		)
		(pad "2" smd circle
			(at 0.40005 0 90)
			(size 0 0)
			(layers "F.Cu" "F.Mask" "F.Paste")
			(net "GND")
		)
	)
	(footprint ""
		(layer "F.Cu")
		(at 142.367254 -57.332626)
		(property "Reference" "R6837"
			(at 0 0 0)
			(layer "F.SilkS")
			(hide yes)
			(effects
				(font
					(size 1.27 1.27)
				)
			)
		)
		(property "Value" ""
			(at 0 0 0)
			(layer "F.Fab")
			(effects
				(font
					(size 1.27 1.27)
				)
			)
		)
		(duplicate_pad_numbers_are_jumpers no)
		(fp_line
			(start -0.7874 -0.4064)
			(end 0.7874 -0.4064)
			(stroke
				(width 0.1524)
				(type default)
			)
			(layer "F.SilkS")
		)
		(fp_line
			(start -0.7874 0.4064)
			(end -0.7874 -0.4064)
			(stroke
				(width 0.1524)
				(type default)
			)
			(layer "F.SilkS")
		)
		(fp_line
			(start 0.7874 -0.4064)
			(end 0.7874 0.4064)
			(stroke
				(width 0.1524)
				(type default)
			)
			(layer "F.SilkS")
		)
		(fp_line
			(start 0.7874 0.4064)
			(end -0.7874 0.4064)
			(stroke
				(width 0.1524)
				(type default)
			)
			(layer "F.SilkS")
		)
		(fp_line
			(start -0.67945 -0.305054)
			(end -0.12065 -0.305054)
			(stroke
				(width 0.1)
				(type default)
			)
			(layer "F.Fab")
		)
		(fp_line
			(start -0.67945 0.3048)
			(end -0.67945 -0.305054)
			(stroke
				(width 0.1)
				(type default)
			)
			(layer "F.Fab")
		)
		(fp_line
			(start -0.12065 -0.305054)
			(end -0.12065 -0.2794)
			(stroke
				(width 0.1)
				(type default)
			)
			(layer "F.Fab")
		)
		(fp_line
			(start -0.12065 -0.2794)
			(end 0.12065 -0.2794)
			(stroke
				(width 0.1)
				(type default)
			)
			(layer "F.Fab")
		)
		(fp_line
			(start -0.12065 0.2794)
			(end -0.12065 0.3048)
			(stroke
				(width 0.1)
				(type default)
			)
			(layer "F.Fab")
		)
		(fp_line
			(start -0.12065 0.3048)
			(end -0.67945 0.3048)
			(stroke
				(width 0.1)
				(type default)
			)
			(layer "F.Fab")
		)
		(fp_line
			(start 0.120396 0.2794)
			(end -0.12065 0.2794)
			(stroke
				(width 0.1)
				(type default)
			)
			(layer "F.Fab")
		)
		(fp_line
			(start 0.120396 0.3048)
			(end 0.120396 0.2794)
			(stroke
				(width 0.1)
				(type default)
			)
			(layer "F.Fab")
		)
		(fp_line
			(start 0.12065 -0.3048)
			(end 0.67945 -0.3048)
			(stroke
				(width 0.1)
				(type default)
			)
			(layer "F.Fab")
		)
		(fp_line
			(start 0.12065 -0.2794)
			(end 0.12065 -0.3048)
			(stroke
				(width 0.1)
				(type default)
			)
			(layer "F.Fab")
		)
		(fp_line
			(start 0.67945 -0.3048)
			(end 0.67945 0.3048)
			(stroke
				(width 0.1)
				(type default)
			)
			(layer "F.Fab")
		)
		(fp_line
			(start 0.67945 0.3048)
			(end 0.120396 0.3048)
			(stroke
				(width 0.1)
				(type default)
			)
			(layer "F.Fab")
		)
		(pad "1" smd circle
			(at -0.40005 0)
			(size 0 0)
			(layers "F.Cu" "F.Mask" "F.Paste")
			(net "SSD4_PWR_EN_R")
		)
		(pad "2" smd circle
			(at 0.40005 0)
			(size 0 0)
			(layers "F.Cu" "F.Mask" "F.Paste")
			(net "GND")
		)
	)
	(footprint ""
		(layer "F.Cu")
		(at 305.147218 -21.37156)
		(property "Reference" "C3946"
			(at 0 0 0)
			(layer "F.SilkS")
			(hide yes)
			(effects
				(font
					(size 1.27 1.27)
				)
			)
		)
		(property "Value" ""
			(at 0 0 0)
			(layer "F.Fab")
			(effects
				(font
					(size 1.27 1.27)
				)
			)
		)
		(duplicate_pad_numbers_are_jumpers no)
		(fp_line
			(start -0.7874 -0.4064)
			(end 0.7874 -0.4064)
			(stroke
				(width 0.1524)
				(type default)
			)
			(layer "F.SilkS")
		)
		(fp_line
			(start -0.7874 0.4064)
			(end -0.7874 -0.4064)
			(stroke
				(width 0.1524)
				(type default)
			)
			(layer "F.SilkS")
		)
		(fp_line
			(start 0.7874 -0.4064)
			(end 0.7874 0.4064)
			(stroke
				(width 0.1524)
				(type default)
			)
			(layer "F.SilkS")
		)
		(fp_line
			(start 0.7874 0.4064)
			(end -0.7874 0.4064)
			(stroke
				(width 0.1524)
				(type default)
			)
			(layer "F.SilkS")
		)
		(fp_line
			(start -0.67945 -0.305054)
			(end -0.12065 -0.305054)
			(stroke
				(width 0.1)
				(type default)
			)
			(layer "F.Fab")
		)
		(fp_line
			(start -0.67945 0.3048)
			(end -0.67945 -0.305054)
			(stroke
				(width 0.1)
				(type default)
			)
			(layer "F.Fab")
		)
		(fp_line
			(start -0.12065 -0.305054)
			(end -0.12065 -0.2794)
			(stroke
				(width 0.1)
				(type default)
			)
			(layer "F.Fab")
		)
		(fp_line
			(start -0.12065 -0.2794)
			(end 0.12065 -0.2794)
			(stroke
				(width 0.1)
				(type default)
			)
			(layer "F.Fab")
		)
		(fp_line
			(start -0.12065 0.2794)
			(end -0.12065 0.3048)
			(stroke
				(width 0.1)
				(type default)
			)
			(layer "F.Fab")
		)
		(fp_line
			(start -0.12065 0.3048)
			(end -0.67945 0.3048)
			(stroke
				(width 0.1)
				(type default)
			)
			(layer "F.Fab")
		)
		(fp_line
			(start 0.120396 0.2794)
			(end -0.12065 0.2794)
			(stroke
				(width 0.1)
				(type default)
			)
			(layer "F.Fab")
		)
		(fp_line
			(start 0.120396 0.3048)
			(end 0.120396 0.2794)
			(stroke
				(width 0.1)
				(type default)
			)
			(layer "F.Fab")
		)
		(fp_line
			(start 0.12065 -0.3048)
			(end 0.67945 -0.3048)
			(stroke
				(width 0.1)
				(type default)
			)
			(layer "F.Fab")
		)
		(fp_line
			(start 0.12065 -0.2794)
			(end 0.12065 -0.3048)
			(stroke
				(width 0.1)
				(type default)
			)
			(layer "F.Fab")
		)
		(fp_line
			(start 0.67945 -0.3048)
			(end 0.67945 0.3048)
			(stroke
				(width 0.1)
				(type default)
			)
			(layer "F.Fab")
		)
		(fp_line
			(start 0.67945 0.3048)
			(end 0.120396 0.3048)
			(stroke
				(width 0.1)
				(type default)
			)
			(layer "F.Fab")
		)
		(pad "1" smd circle
			(at -0.40005 0)
			(size 0 0)
			(layers "F.Cu" "F.Mask" "F.Paste")
			(net "P12V_SSD10")
		)
		(pad "2" smd circle
			(at 0.40005 0)
			(size 0 0)
			(layers "F.Cu" "F.Mask" "F.Paste")
			(net "GND")
		)
	)
	(footprint ""
		(layer "F.Cu")
		(at 55.155084 -53.468524 90)
		(property "Reference" "PC523"
			(at 0 0 90)
			(layer "F.SilkS")
			(hide yes)
			(effects
				(font
					(size 1.27 1.27)
				)
			)
		)
		(property "Value" ""
			(at 0 0 90)
			(layer "F.Fab")
			(effects
				(font
					(size 1.27 1.27)
				)
			)
		)
		(duplicate_pad_numbers_are_jumpers no)
		(fp_line
			(start 1.524 -0.762)
			(end 1.524 0.762)
			(stroke
				(width 0.1524)
				(type default)
			)
			(layer "F.SilkS")
		)
		(fp_line
			(start -1.524 -0.762)
			(end 1.524 -0.762)
			(stroke
				(width 0.1524)
				(type default)
			)
			(layer "F.SilkS")
		)
		(fp_line
			(start 1.524 0.762)
			(end -1.524 0.762)
			(stroke
				(width 0.1524)
				(type default)
			)
			(layer "F.SilkS")
		)
		(fp_line
			(start -1.524 0.762)
			(end -1.524 -0.762)
			(stroke
				(width 0.1524)
				(type default)
			)
			(layer "F.SilkS")
		)
		(fp_line
			(start 1.1049 -0.724916)
			(end -1.1049 -0.724916)
			(stroke
				(width 0.1)
				(type default)
			)
			(layer "F.Fab")
		)
		(fp_line
			(start -1.1049 -0.724916)
			(end -1.1049 0.724916)
			(stroke
				(width 0.1)
				(type default)
			)
			(layer "F.Fab")
		)
		(fp_line
			(start 1.1049 0.724916)
			(end 1.1049 -0.724916)
			(stroke
				(width 0.1)
				(type default)
			)
			(layer "F.Fab")
		)
		(fp_line
			(start -1.1049 0.724916)
			(end 1.1049 0.724916)
			(stroke
				(width 0.1)
				(type default)
			)
			(layer "F.Fab")
		)
		(pad "1" smd rect
			(at -0.889 0 270)
			(size 1.016 1.27)
			(layers "F.Cu" "F.Mask" "F.Paste")
			(net "GND")
		)
		(pad "2" smd rect
			(at 0.889 0 270)
			(size 1.016 1.27)
			(layers "F.Cu" "F.Mask" "F.Paste")
			(net "P3V3_AUX")
		)
	)
	(footprint ""
		(layer "F.Cu")
		(at 448.18554 -27.092148 -90)
		(property "Reference" "R5749"
			(at 0 0 270)
			(layer "F.SilkS")
			(hide yes)
			(effects
				(font
					(size 1.27 1.27)
				)
			)
		)
		(property "Value" ""
			(at 0 0 270)
			(layer "F.Fab")
			(effects
				(font
					(size 1.27 1.27)
				)
			)
		)
		(duplicate_pad_numbers_are_jumpers no)
		(fp_line
			(start -0.7874 0.4064)
			(end -0.7874 -0.4064)
			(stroke
				(width 0.1524)
				(type default)
			)
			(layer "F.SilkS")
		)
		(fp_line
			(start 0.7874 0.4064)
			(end -0.7874 0.4064)
			(stroke
				(width 0.1524)
				(type default)
			)
			(layer "F.SilkS")
		)
		(fp_line
			(start -0.7874 -0.4064)
			(end 0.7874 -0.4064)
			(stroke
				(width 0.1524)
				(type default)
			)
			(layer "F.SilkS")
		)
		(fp_line
			(start 0.7874 -0.4064)
			(end 0.7874 0.4064)
			(stroke
				(width 0.1524)
				(type default)
			)
			(layer "F.SilkS")
		)
		(fp_line
			(start -0.67945 0.3048)
			(end -0.67945 -0.305054)
			(stroke
				(width 0.1)
				(type default)
			)
			(layer "F.Fab")
		)
		(fp_line
			(start -0.12065 0.3048)
			(end -0.67945 0.3048)
			(stroke
				(width 0.1)
				(type default)
			)
			(layer "F.Fab")
		)
		(fp_line
			(start 0.120396 0.3048)
			(end 0.120396 0.2794)
			(stroke
				(width 0.1)
				(type default)
			)
			(layer "F.Fab")
		)
		(fp_line
			(start 0.67945 0.3048)
			(end 0.120396 0.3048)
			(stroke
				(width 0.1)
				(type default)
			)
			(layer "F.Fab")
		)
		(fp_line
			(start -0.12065 0.2794)
			(end -0.12065 0.3048)
			(stroke
				(width 0.1)
				(type default)
			)
			(layer "F.Fab")
		)
		(fp_line
			(start 0.120396 0.2794)
			(end -0.12065 0.2794)
			(stroke
				(width 0.1)
				(type default)
			)
			(layer "F.Fab")
		)
		(fp_line
			(start -0.12065 -0.2794)
			(end 0.12065 -0.2794)
			(stroke
				(width 0.1)
				(type default)
			)
			(layer "F.Fab")
		)
		(fp_line
			(start 0.12065 -0.2794)
			(end 0.12065 -0.3048)
			(stroke
				(width 0.1)
				(type default)
			)
			(layer "F.Fab")
		)
		(fp_line
			(start 0.12065 -0.3048)
			(end 0.67945 -0.3048)
			(stroke
				(width 0.1)
				(type default)
			)
			(layer "F.Fab")
		)
		(fp_line
			(start 0.67945 -0.3048)
			(end 0.67945 0.3048)
			(stroke
				(width 0.1)
				(type default)
			)
			(layer "F.Fab")
		)
		(fp_line
			(start -0.67945 -0.305054)
			(end -0.12065 -0.305054)
			(stroke
				(width 0.1)
				(type default)
			)
			(layer "F.Fab")
		)
		(fp_line
			(start -0.12065 -0.305054)
			(end -0.12065 -0.2794)
			(stroke
				(width 0.1)
				(type default)
			)
			(layer "F.Fab")
		)
		(pad "1" smd circle
			(at -0.40005 0 270)
			(size 0 0)
			(layers "F.Cu" "F.Mask" "F.Paste")
			(net "P3V3_SSD15")
		)
		(pad "2" smd circle
			(at 0.40005 0 270)
			(size 0 0)
			(layers "F.Cu" "F.Mask" "F.Paste")
			(net "SSD15_LED_ISO_N")
		)
	)
)
